(kicad_pcb
	(version 20241229)
	(generator "pcbnew")
	(generator_version "9.0")
	(general
		(thickness 1.62)
		(legacy_teardrops no)
	)
	(paper "A3")
	(title_block
		(title "COM Express 7 Baseboard")
		(date "2025-02-04")
		(rev "1.1.2")
		(company "Antmicro Ltd")
		(comment 1 "www.antmicro.com")
		(comment 9 "footprints 25-26 of 802")
	)
	(layers
		(0 "F.Cu" signal)
		(4 "In1.Cu" signal)
		(6 "In2.Cu" signal)
		(8 "In3.Cu" signal)
		(10 "In4.Cu" signal)
		(12 "In5.Cu" signal)
		(14 "In6.Cu" signal)
		(2 "B.Cu" signal)
		(9 "F.Adhes" user "F.Adhesive")
		(11 "B.Adhes" user "B.Adhesive")
		(13 "F.Paste" user)
		(15 "B.Paste" user)
		(5 "F.SilkS" user "F.Silkscreen")
		(7 "B.SilkS" user "B.Silkscreen")
		(1 "F.Mask" user)
		(3 "B.Mask" user)
		(17 "Dwgs.User" user "User.Drawings")
		(19 "Cmts.User" user "User.Comments")
		(21 "Eco1.User" user "User.Eco1")
		(23 "Eco2.User" user "User.Eco2")
		(25 "Edge.Cuts" user)
		(27 "Margin" user)
		(31 "F.CrtYd" user "F.Courtyard")
		(29 "B.CrtYd" user "B.Courtyard")
		(35 "F.Fab" user)
		(33 "B.Fab" user)
	)
	(footprint "antmicro-footprints:C_0201"
		(layer "F.Cu")
		(at 138.172 147.31 90)
		(descr "Capacitor SMD 0201")
		(tags "capacitor SMD 0201")
		(property "Reference" "C181"
			(at -4.1 0.578 90)
			(layer "F.SilkS")
			(effects
				(font
					(size 0.7 0.7)
					(thickness 0.15)
				)
				(justify left bottom)
			)
		)
		(property "Value" "C_100n_0201_25V"
			(at 0 1.4 90)
			(layer "F.Fab")
			(effects
				(font
					(size 0.7 0.7)
					(thickness 0.15)
				)
				(justify left bottom)
			)
		)
		(property "Datasheet" "https://product.tdk.com/en/search/capacitor/ceramic/mlcc/info?part_no=C0603X5R1E104K030BB"
			(at 0 0 90)
			(layer "F.Fab")
			(hide yes)
			(effects
				(font
					(size 1.27 1.27)
					(thickness 0.15)
				)
			)
		)
		(property "Author" "Antmicro"
			(at 285.482 9.138 0)
			(layer "F.Fab")
			(hide yes)
			(effects
				(font
					(size 1 1)
					(thickness 0.15)
				)
			)
		)
		(property "Dielectric" ""
			(at 285.482 9.138 0)
			(layer "F.Fab")
			(hide yes)
			(effects
				(font
					(size 1 1)
					(thickness 0.15)
				)
			)
		)
		(property "License" "Apache-2.0"
			(at 285.482 9.138 0)
			(layer "F.Fab")
			(hide yes)
			(effects
				(font
					(size 1 1)
					(thickness 0.15)
				)
			)
		)
		(property "MPN" "C0603X5R1E104K030BB"
			(at 285.482 9.138 0)
			(layer "F.Fab")
			(hide yes)
			(effects
				(font
					(size 1 1)
					(thickness 0.15)
				)
			)
		)
		(property "Manufacturer" "TDK"
			(at 285.482 9.138 0)
			(layer "F.Fab")
			(hide yes)
			(effects
				(font
					(size 1 1)
					(thickness 0.15)
				)
			)
		)
		(property "Public" "False"
			(at 285.482 9.138 0)
			(layer "F.Fab")
			(hide yes)
			(effects
				(font
					(size 1 1)
					(thickness 0.15)
				)
			)
		)
		(property "Val" "100n"
			(at 285.482 9.138 0)
			(layer "F.Fab")
			(hide yes)
			(effects
				(font
					(size 1 1)
					(thickness 0.15)
				)
			)
		)
		(property "Voltage" "25V"
			(at 285.482 9.138 0)
			(layer "F.Fab")
			(hide yes)
			(effects
				(font
					(size 1 1)
					(thickness 0.15)
				)
			)
		)
		(sheetname "KR to SFI #2")
		(sheetfile "kr_sfi.kicad_sch")
		(attr smd)
		(fp_rect
			(start -0.7 -0.35)
			(end 0.7 0.35)
			(stroke
				(width 0.05)
				(type default)
			)
			(fill no)
			(layer "F.CrtYd")
		)
		(fp_rect
			(start 0.3 0.15)
			(end -0.301 -0.149)
			(stroke
				(width 0.15)
				(type solid)
			)
			(fill no)
			(layer "F.Fab")
		)
		(pad "" smd roundrect
			(at -0.349 -0.002 90)
			(size 0.318 0.36)
			(layers "F.Paste")
			(roundrect_rratio 0.25)
			(teardrops
				(best_length_ratio 0.2)
				(max_length 1)
				(best_width_ratio 0.9)
				(max_width 2)
				(curved_edges yes)
				(filter_ratio 0.9)
				(enabled yes)
				(allow_two_segments yes)
				(prefer_zone_connections yes)
			)
		)
		(pad "" smd roundrect
			(at 0.341 -0.002 90)
			(size 0.318 0.36)
			(layers "F.Paste")
			(roundrect_rratio 0.25)
			(teardrops
				(best_length_ratio 0.2)
				(max_length 1)
				(best_width_ratio 0.9)
				(max_width 2)
				(curved_edges yes)
				(filter_ratio 0.9)
				(enabled yes)
				(allow_two_segments yes)
				(prefer_zone_connections yes)
			)
		)
		(pad "1" smd roundrect
			(at -0.321 -0.002 90)
			(size 0.46 0.4)
			(layers "F.Cu" "F.Mask")
			(roundrect_rratio 0.25)
			(net 121 "/2xSFP+/10GKR_SFP1.TX-")
			(pintype "passive")
			(teardrops
				(best_length_ratio 0.2)
				(max_length 1)
				(best_width_ratio 0.9)
				(max_width 2)
				(curved_edges yes)
				(filter_ratio 0.9)
				(enabled yes)
				(allow_two_segments yes)
				(prefer_zone_connections yes)
			)
		)
		(pad "2" smd roundrect
			(at 0.32 -0.002 90)
			(size 0.46 0.4)
			(layers "F.Cu" "F.Mask")
			(roundrect_rratio 0.25)
			(net 122 "/2xSFP+/KR to SFI #2/KR_C.TX-")
			(pintype "passive")
			(teardrops
				(best_length_ratio 0.2)
				(max_length 1)
				(best_width_ratio 0.9)
				(max_width 2)
				(curved_edges yes)
				(filter_ratio 0.9)
				(enabled yes)
				(allow_two_segments yes)
				(prefer_zone_connections yes)
			)
		)
	)
	(footprint "antmicro-footprints:PLCC4_3.2x2.8mm"
		(layer "F.Cu")
		(at 102.44 77.555 90)
		(property "Reference" "D17"
			(at -0.905 -2.94 90)
			(unlocked yes)
			(layer "F.SilkS")
			(effects
				(font
					(size 0.7 0.7)
					(thickness 0.15)
				)
				(justify left bottom)
			)
		)
		(property "Value" "LED_RGB_PLCC4_ASMB_MTB1_0A3A2"
			(at 0 2.7 90)
			(unlocked yes)
			(layer "F.Fab")
			(effects
				(font
					(size 0.7 0.7)
					(thickness 0.15)
				)
				(justify left bottom)
			)
		)
		(property "Datasheet" "https://docs.broadcom.com/doc/AV02-4194EN"
			(at 0 0 90)
			(layer "F.Fab")
			(hide yes)
			(effects
				(font
					(size 1.27 1.27)
					(thickness 0.15)
				)
			)
		)
		(property "Author" "Antmicro"
			(at 179.995 -24.885 0)
			(layer "F.Fab")
			(hide yes)
			(effects
				(font
					(size 1 1)
					(thickness 0.15)
				)
			)
		)
		(property "Color" "R, G, B"
			(at 179.995 -24.885 0)
			(layer "F.Fab")
			(hide yes)
			(effects
				(font
					(size 1 1)
					(thickness 0.15)
				)
			)
		)
		(property "License" "Apache-2.0"
			(at 179.995 -24.885 0)
			(layer "F.Fab")
			(hide yes)
			(effects
				(font
					(size 1 1)
					(thickness 0.15)
				)
			)
		)
		(property "MPN" "ASMB-MTB1-0A3A2"
			(at 179.995 -24.885 0)
			(layer "F.Fab")
			(hide yes)
			(effects
				(font
					(size 1 1)
					(thickness 0.15)
				)
			)
		)
		(property "Manufacturer" "Avago Technologies"
			(at 179.995 -24.885 0)
			(layer "F.Fab")
			(hide yes)
			(effects
				(font
					(size 1 1)
					(thickness 0.15)
				)
			)
		)
		(sheetname "Misc")
		(sheetfile "misc.kicad_sch")
		(attr smd)
		(fp_line
			(start -1.75 -1.491)
			(end 1.947 -1.491)
			(stroke
				(width 0.15)
				(type solid)
			)
			(layer "F.SilkS")
		)
		(fp_line
			(start -1.953 1.509)
			(end 1.947 1.509)
			(stroke
				(width 0.15)
				(type solid)
			)
			(layer "F.SilkS")
		)
		(fp_circle
			(center -2 -1.45)
			(end -1.95 -1.45)
			(stroke
				(width 0.15)
				(type solid)
			)
			(fill yes)
			(layer "F.SilkS")
		)
		(fp_rect
			(start -2.25 -1.65)
			(end 2.24 1.65)
			(stroke
				(width 0.05)
				(type solid)
			)
			(fill no)
			(layer "F.CrtYd")
		)
		(fp_line
			(start 1.597 -1.391)
			(end -1.603 -1.391)
			(stroke
				(width 0.15)
				(type solid)
			)
			(layer "F.Fab")
		)
		(fp_line
			(start -0.603 -1.391)
			(end -1.603 -0.391)
			(stroke
				(width 0.15)
				(type solid)
			)
			(layer "F.Fab")
		)
		(fp_line
			(start -1.603 -1.391)
			(end -1.603 1.409)
			(stroke
				(width 0.15)
				(type solid)
			)
			(layer "F.Fab")
		)
		(fp_line
			(start 1.597 1.409)
			(end 1.597 -1.391)
			(stroke
				(width 0.15)
				(type solid)
			)
			(layer "F.Fab")
		)
		(fp_line
			(start -1.603 1.409)
			(end 1.597 1.409)
			(stroke
				(width 0.15)
				(type solid)
			)
			(layer "F.Fab")
		)
		(fp_circle
			(center -0.003 0.009)
			(end 1.117 0.009)
			(stroke
				(width 0.15)
				(type solid)
			)
			(fill no)
			(layer "F.Fab")
		)
		(pad "1" smd rect
			(at -1.255 -0.74 90)
			(size 1.5 1.1)
			(layers "F.Cu" "F.Mask" "F.Paste")
			(net 129 "Net-(D17-C_{R})")
			(pinfunction "C_{R}")
			(pintype "passive")
			(teardrops
				(best_length_ratio 0.2)
				(max_length 1)
				(best_width_ratio 0.9)
				(max_width 2)
				(curved_edges yes)
				(filter_ratio 0.9)
				(enabled yes)
				(allow_two_segments yes)
				(prefer_zone_connections yes)
			)
		)
		(pad "2" smd rect
			(at 1.245 -0.74 90)
			(size 1.5 1.1)
			(layers "F.Cu" "F.Mask" "F.Paste")
			(net 130 "Net-(D17-C_{G})")
			(pinfunction "C_{G}")
			(pintype "passive")
			(teardrops
				(best_length_ratio 0.2)
				(max_length 1)
				(best_width_ratio 0.9)
				(max_width 2)
				(curved_edges yes)
				(filter_ratio 0.9)
				(enabled yes)
				(allow_two_segments yes)
				(prefer_zone_connections yes)
			)
		)
		(pad "3" smd rect
			(at 1.245 0.76 90)
			(size 1.5 1.1)
			(layers "F.Cu" "F.Mask" "F.Paste")
			(net 131 "Net-(D17-C_{B})")
			(pinfunction "C_{B}")
			(pintype "passive")
			(teardrops
				(best_length_ratio 0.2)
				(max_length 1)
				(best_width_ratio 0.9)
				(max_width 2)
				(curved_edges yes)
				(filter_ratio 0.9)
				(enabled yes)
				(allow_two_segments yes)
				(prefer_zone_connections yes)
			)
		)
		(pad "4" smd rect
			(at -1.255 0.76 90)
			(size 1.5 1.1)
			(layers "F.Cu" "F.Mask" "F.Paste")
			(net 52 "+5V")
			(pinfunction "A")
			(pintype "passive")
			(teardrops
				(best_length_ratio 0.2)
				(max_length 1)
				(best_width_ratio 0.9)
				(max_width 2)
				(curved_edges yes)
				(filter_ratio 0.9)
				(enabled yes)
				(allow_two_segments yes)
				(prefer_zone_connections yes)
			)
		)
	)
)
